(kicad_pcb
	(version 20260206)
	(generator "pcbnew")
	(generator_version "10.0")
	(general
		(thickness 1.6)
		(legacy_teardrops no)
	)
	(paper "A4")
	(title_block
		(title "01162023_DA0F0TEBIF0_F0T_Expander_BD_F_brd_V02_OCP.brd")
		(comment 1 "Grand Teton / footprints 3552-3560 of 9728")
	)
	(layers
		(0 "F.Cu" signal "TOP")
		(4 "In1.Cu" signal "GND")
		(6 "In2.Cu" signal "VCC")
		(8 "In3.Cu" signal "VCC1")
		(10 "In4.Cu" signal "GND1")
		(12 "In5.Cu" signal "IN1")
		(14 "In6.Cu" signal "GND2")
		(16 "In7.Cu" signal "IN2")
		(18 "In8.Cu" signal "GND3")
		(20 "In9.Cu" signal "IN3")
		(22 "In10.Cu" signal "GND4")
		(24 "In11.Cu" signal "IN4")
		(26 "In12.Cu" signal "GND5")
		(28 "In13.Cu" signal "IN5")
		(30 "In14.Cu" signal "GND6")
		(32 "In15.Cu" signal "IN6")
		(34 "In16.Cu" signal "GND7")
		(2 "B.Cu" signal "BOTTOM")
		(9 "F.Adhes" user "F.Adhesive")
		(11 "B.Adhes" user "B.Adhesive")
		(13 "F.Paste" user "Package Geometry/Pastemask Top")
		(15 "B.Paste" user "Package Geometry/Pastemask Bottom")
		(5 "F.SilkS" user "Ref Des/Silkscreen Top")
		(7 "B.SilkS" user "Ref Des/Silkscreen Bottom")
		(1 "F.Mask" user "Board Geometry/Soldermask Top")
		(3 "B.Mask" user "Board Geometry/Soldermask Bottom")
		(17 "Dwgs.User" user "User.Drawings")
		(19 "Cmts.User" user "User.Comments")
		(21 "Eco1.User" user "User.Eco1")
		(23 "Eco2.User" user "User.Eco2")
		(25 "Edge.Cuts" user "Board Geometry/Outline")
		(27 "Margin" user)
		(31 "F.CrtYd" user "Package Geometry/Place Bound Top")
		(29 "B.CrtYd" user "Package Geometry/Place Bound Bottom")
		(35 "F.Fab" user "Ref Des/Assembly Top")
		(33 "B.Fab" user "Ref Des/Assembly Bottom")
	)
	(footprint ""
		(layer "F.Cu")
		(at 383.05613 -115.590574 90)
		(property "Reference" "U39"
			(at 2.542286 -0.661416 0)
			(unlocked yes)
			(layer "F.SilkS")
			(effects
				(font
					(size 0.7874 0.5842)
					(thickness 0.1524)
				)
			)
		)
		(property "Value" ""
			(at 0 0 90)
			(layer "F.Fab")
			(effects
				(font
					(size 1.27 1.27)
				)
			)
		)
		(duplicate_pad_numbers_are_jumpers no)
		(fp_line
			(start -1.949958 -1.610106)
			(end 1.949958 -1.610106)
			(stroke
				(width 0.1524)
				(type default)
			)
			(layer "F.SilkS")
		)
		(fp_line
			(start 1.949958 -1.560068)
			(end 1.949958 1.610106)
			(stroke
				(width 0.1524)
				(type default)
			)
			(layer "F.SilkS")
		)
		(fp_line
			(start 1.949958 1.610106)
			(end -1.949958 1.610106)
			(stroke
				(width 0.1524)
				(type default)
			)
			(layer "F.SilkS")
		)
		(fp_line
			(start -1.949958 1.610106)
			(end -1.949958 -1.610106)
			(stroke
				(width 0.1524)
				(type default)
			)
			(layer "F.SilkS")
		)
		(fp_line
			(start 0.750062 -1.560068)
			(end 0.750062 1.560068)
			(stroke
				(width 0.1)
				(type default)
			)
			(layer "F.Fab")
		)
		(fp_line
			(start -0.750062 -1.560068)
			(end 0.750062 -1.560068)
			(stroke
				(width 0.1)
				(type default)
			)
			(layer "F.Fab")
		)
		(fp_line
			(start 0.750062 1.560068)
			(end -0.750062 1.560068)
			(stroke
				(width 0.1)
				(type default)
			)
			(layer "F.Fab")
		)
		(fp_line
			(start -0.750062 1.560068)
			(end -0.750062 -1.560068)
			(stroke
				(width 0.1)
				(type default)
			)
			(layer "F.Fab")
		)
		(pad "D" smd rect
			(at 1.100074 0)
			(size 1.016 1.4224)
			(layers "F.Cu" "F.Mask" "F.Paste")
			(net "HP_NIC6_EN")
		)
		(pad "G" smd rect
			(at -1.100074 -0.94996)
			(size 1.016 1.4224)
			(layers "F.Cu" "F.Mask" "F.Paste")
			(net "PRSNT_NIC6_R_N")
		)
		(pad "S" smd rect
			(at -1.100074 0.94996)
			(size 1.016 1.4224)
			(layers "F.Cu" "F.Mask" "F.Paste")
			(net "GND")
		)
	)
	(footprint ""
		(layer "F.Cu")
		(at 236.927136 -266.873228 180)
		(property "Reference" "R6137"
			(at 0 0 180)
			(layer "F.SilkS")
			(hide yes)
			(effects
				(font
					(size 1.27 1.27)
				)
			)
		)
		(property "Value" ""
			(at 0 0 180)
			(layer "F.Fab")
			(effects
				(font
					(size 1.27 1.27)
				)
			)
		)
		(duplicate_pad_numbers_are_jumpers no)
		(fp_line
			(start 2.576322 1.1303)
			(end -2.576322 1.1303)
			(stroke
				(width 0.1524)
				(type default)
			)
			(layer "F.SilkS")
		)
		(fp_line
			(start 2.576322 -1.1303)
			(end 2.576322 1.1303)
			(stroke
				(width 0.1524)
				(type default)
			)
			(layer "F.SilkS")
		)
		(fp_line
			(start -2.576322 1.1303)
			(end -2.576322 -1.1303)
			(stroke
				(width 0.1524)
				(type default)
			)
			(layer "F.SilkS")
		)
		(fp_line
			(start -2.576322 -1.1303)
			(end 2.576322 -1.1303)
			(stroke
				(width 0.1524)
				(type default)
			)
			(layer "F.SilkS")
		)
		(fp_line
			(start 1.649984 0.899922)
			(end 1.649984 -0.899922)
			(stroke
				(width 0.1)
				(type default)
			)
			(layer "F.Fab")
		)
		(fp_line
			(start 1.649984 -0.899922)
			(end -1.649984 -0.899922)
			(stroke
				(width 0.1)
				(type default)
			)
			(layer "F.Fab")
		)
		(fp_line
			(start -1.649984 0.899922)
			(end 1.649984 0.899922)
			(stroke
				(width 0.1)
				(type default)
			)
			(layer "F.Fab")
		)
		(fp_line
			(start -1.649984 -0.899922)
			(end -1.649984 0.899922)
			(stroke
				(width 0.1)
				(type default)
			)
			(layer "F.Fab")
		)
		(pad "1A" smd rect
			(at -1.700022 0 180)
			(size 1.4986 2.0066)
			(layers "F.Cu" "F.Mask" "F.Paste")
			(net "P1V25_PEX2")
		)
		(pad "1B" smd rect
			(at -1.077722 0 180)
			(size 0.254 0.508)
			(layers "F.Cu" "F.Mask" "F.Paste")
			(net "P1V25_PEX2")
		)
		(pad "2A" smd rect
			(at 1.700022 0 180)
			(size 1.4986 2.0066)
			(layers "F.Cu" "F.Mask" "F.Paste")
			(net "P1V25_SERDES_VDDPLL_PEX2")
		)
		(pad "2B" smd rect
			(at 1.077722 0 180)
			(size 0.254 0.508)
			(layers "F.Cu" "F.Mask" "F.Paste")
			(net "P1V25_SERDES_VDDPLL_PEX2")
		)
	)
	(footprint ""
		(layer "F.Cu")
		(at 80.000602 -356.244906 90)
		(property "Reference" "C147"
			(at 0 0 90)
			(layer "F.SilkS")
			(hide yes)
			(effects
				(font
					(size 1.27 1.27)
				)
			)
		)
		(property "Value" ""
			(at 0 0 90)
			(layer "F.Fab")
			(effects
				(font
					(size 1.27 1.27)
				)
			)
		)
		(duplicate_pad_numbers_are_jumpers no)
		(fp_line
			(start 0.299974 -0.150114)
			(end 0.299974 0.150114)
			(stroke
				(width 0.1)
				(type default)
			)
			(layer "F.Fab")
		)
		(fp_line
			(start -0.299974 -0.150114)
			(end 0.299974 -0.150114)
			(stroke
				(width 0.1)
				(type default)
			)
			(layer "F.Fab")
		)
		(fp_line
			(start 0.299974 0.150114)
			(end -0.299974 0.150114)
			(stroke
				(width 0.1)
				(type default)
			)
			(layer "F.Fab")
		)
		(fp_line
			(start -0.299974 0.150114)
			(end -0.299974 -0.150114)
			(stroke
				(width 0.1)
				(type default)
			)
			(layer "F.Fab")
		)
		(pad "1" smd rect
			(at -0.2667 0 90)
			(size 0.3048 0.381)
			(layers "F.Cu" "F.Mask" "F.Paste")
			(net "P5E_PEX0_STN6_TX_DP<102>")
		)
		(pad "2" smd rect
			(at 0.2667 0 90)
			(size 0.3048 0.381)
			(layers "F.Cu" "F.Mask" "F.Paste")
			(net "P5E_PEX0_STN6_TX_C_DP<102>")
		)
	)
	(footprint ""
		(layer "F.Cu")
		(at 43.792394 -28.225242 180)
		(property "Reference" "C80"
			(at 0 0 180)
			(layer "F.SilkS")
			(hide yes)
			(effects
				(font
					(size 1.27 1.27)
				)
			)
		)
		(property "Value" ""
			(at 0 0 180)
			(layer "F.Fab")
			(effects
				(font
					(size 1.27 1.27)
				)
			)
		)
		(duplicate_pad_numbers_are_jumpers no)
		(fp_line
			(start 0.299974 0.150114)
			(end -0.299974 0.150114)
			(stroke
				(width 0.1)
				(type default)
			)
			(layer "F.Fab")
		)
		(fp_line
			(start 0.299974 -0.150114)
			(end 0.299974 0.150114)
			(stroke
				(width 0.1)
				(type default)
			)
			(layer "F.Fab")
		)
		(fp_line
			(start -0.299974 0.150114)
			(end -0.299974 -0.150114)
			(stroke
				(width 0.1)
				(type default)
			)
			(layer "F.Fab")
		)
		(fp_line
			(start -0.299974 -0.150114)
			(end 0.299974 -0.150114)
			(stroke
				(width 0.1)
				(type default)
			)
			(layer "F.Fab")
		)
		(pad "1" smd rect
			(at -0.2667 0 180)
			(size 0.3048 0.381)
			(layers "F.Cu" "F.Mask" "F.Paste")
			(net "P5E_PEX0_STN2_TX_DN<40>")
		)
		(pad "2" smd rect
			(at 0.2667 0 180)
			(size 0.3048 0.381)
			(layers "F.Cu" "F.Mask" "F.Paste")
			(net "P5E_PEX0_STN2_TX_C_DN<40>")
		)
	)
	(footprint ""
		(layer "F.Cu")
		(at 23.326852 -172.974508 90)
		(property "Reference" "PJ2"
			(at 0 0 90)
			(layer "F.SilkS")
			(hide yes)
			(effects
				(font
					(size 1.27 1.27)
				)
			)
		)
		(property "Value" ""
			(at 0 0 90)
			(layer "F.Fab")
			(effects
				(font
					(size 1.27 1.27)
				)
			)
		)
		(duplicate_pad_numbers_are_jumpers no)
		(pad "1" smd circle
			(at -0.40005 0 180)
			(size 0 0)
			(layers "F.Cu" "F.Mask" "F.Paste")
			(net "SH_P5V_AUX_FB")
		)
		(pad "2" smd rect
			(at 0.40005 0 270)
			(size 0.4572 0.508)
			(layers "F.Cu" "F.Mask" "F.Paste")
			(net "P5V_AUX")
		)
		(zone
			(layer "F.Cu")
			(hatch none 0.5)
			(connect_pads
				(clearance 0)
			)
			(min_thickness 0.25)
			(keepout
				(tracks allowed)
				(vias not_allowed)
				(pads allowed)
				(copperpour not_allowed)
				(footprints allowed)
			)
			(placement
				(enabled no)
				(sheetname "")
			)
			(fill
				(thermal_gap 0.5)
				(thermal_bridge_width 0.5)
				(island_removal_mode 0)
			)
			(polygon
				(pts
					(xy 23.631652 -173.660308) (xy 23.022052 -173.660308) (xy 23.022052 -172.288708) (xy 23.631652 -172.288708)
				)
			)
		)
	)
	(footprint ""
		(layer "F.Cu")
		(at 494.303558 -549.60774 180)
		(property "Reference" "SCREW_1"
			(at -3.2385 -1.402334 0)
			(unlocked yes)
			(layer "B.SilkS")
			(effects
				(font
					(size 0.7874 0.5842)
					(thickness 0.1524)
				)
				(justify mirror)
			)
		)
		(property "Value" ""
			(at 0 0 180)
			(layer "F.Fab")
			(effects
				(font
					(size 1.27 1.27)
				)
			)
		)
		(duplicate_pad_numbers_are_jumpers no)
		(pad "1" thru_hole circle
			(at 0 0 180)
			(size 0.4572 0.4572)
			(drill 0.2032)
			(layers "*.Cu" "*.Mask")
			(remove_unused_layers no)
			(net "Net_9163")
			(clearance 0.127)
			(thermal_gap 0.127)
			(padstack
				(mode front_inner_back)
				(layer "Inner"
					(shape circle)
					(size 0.4572 0.4572)
					(clearance 0.127)
				)
				(layer "B.Cu"
					(shape circle)
					(size 0.508 0.508)
					(clearance 0.1016)
				)
			)
		)
	)
	(footprint ""
		(layer "F.Cu")
		(at 452.324978 -14.735302 180)
		(property "Reference" "C2742"
			(at 0 0 180)
			(layer "F.SilkS")
			(hide yes)
			(effects
				(font
					(size 1.27 1.27)
				)
			)
		)
		(property "Value" ""
			(at 0 0 180)
			(layer "F.Fab")
			(effects
				(font
					(size 1.27 1.27)
				)
			)
		)
		(duplicate_pad_numbers_are_jumpers no)
		(fp_line
			(start 0.7874 0.4064)
			(end -0.7874 0.4064)
			(stroke
				(width 0.1524)
				(type default)
			)
			(layer "F.SilkS")
		)
		(fp_line
			(start 0.7874 -0.4064)
			(end 0.7874 0.4064)
			(stroke
				(width 0.1524)
				(type default)
			)
			(layer "F.SilkS")
		)
		(fp_line
			(start -0.7874 0.4064)
			(end -0.7874 -0.4064)
			(stroke
				(width 0.1524)
				(type default)
			)
			(layer "F.SilkS")
		)
		(fp_line
			(start -0.7874 -0.4064)
			(end 0.7874 -0.4064)
			(stroke
				(width 0.1524)
				(type default)
			)
			(layer "F.SilkS")
		)
		(fp_line
			(start 0.67945 0.3048)
			(end 0.120396 0.3048)
			(stroke
				(width 0.1)
				(type default)
			)
			(layer "F.Fab")
		)
		(fp_line
			(start 0.67945 -0.3048)
			(end 0.67945 0.3048)
			(stroke
				(width 0.1)
				(type default)
			)
			(layer "F.Fab")
		)
		(fp_line
			(start 0.12065 -0.2794)
			(end 0.12065 -0.3048)
			(stroke
				(width 0.1)
				(type default)
			)
			(layer "F.Fab")
		)
		(fp_line
			(start 0.12065 -0.3048)
			(end 0.67945 -0.3048)
			(stroke
				(width 0.1)
				(type default)
			)
			(layer "F.Fab")
		)
		(fp_line
			(start 0.120396 0.3048)
			(end 0.120396 0.2794)
			(stroke
				(width 0.1)
				(type default)
			)
			(layer "F.Fab")
		)
		(fp_line
			(start 0.120396 0.2794)
			(end -0.12065 0.2794)
			(stroke
				(width 0.1)
				(type default)
			)
			(layer "F.Fab")
		)
		(fp_line
			(start -0.12065 0.3048)
			(end -0.67945 0.3048)
			(stroke
				(width 0.1)
				(type default)
			)
			(layer "F.Fab")
		)
		(fp_line
			(start -0.12065 0.2794)
			(end -0.12065 0.3048)
			(stroke
				(width 0.1)
				(type default)
			)
			(layer "F.Fab")
		)
		(fp_line
			(start -0.12065 -0.2794)
			(end 0.12065 -0.2794)
			(stroke
				(width 0.1)
				(type default)
			)
			(layer "F.Fab")
		)
		(fp_line
			(start -0.12065 -0.305054)
			(end -0.12065 -0.2794)
			(stroke
				(width 0.1)
				(type default)
			)
			(layer "F.Fab")
		)
		(fp_line
			(start -0.67945 0.3048)
			(end -0.67945 -0.305054)
			(stroke
				(width 0.1)
				(type default)
			)
			(layer "F.Fab")
		)
		(fp_line
			(start -0.67945 -0.305054)
			(end -0.12065 -0.305054)
			(stroke
				(width 0.1)
				(type default)
			)
			(layer "F.Fab")
		)
		(pad "1" smd circle
			(at -0.40005 0 180)
			(size 0 0)
			(layers "F.Cu" "F.Mask" "F.Paste")
			(net "GND")
		)
		(pad "2" smd circle
			(at 0.40005 0 180)
			(size 0 0)
			(layers "F.Cu" "F.Mask" "F.Paste")
			(net "P3V3_SSD15")
		)
	)
	(footprint ""
		(layer "F.Cu")
		(at 232.591864 -204.44206 90)
		(property "Reference" "R5529"
			(at 0 0 90)
			(layer "F.SilkS")
			(hide yes)
			(effects
				(font
					(size 1.27 1.27)
				)
			)
		)
		(property "Value" ""
			(at 0 0 90)
			(layer "F.Fab")
			(effects
				(font
					(size 1.27 1.27)
				)
			)
		)
		(duplicate_pad_numbers_are_jumpers no)
		(fp_line
			(start 0.7874 -0.4064)
			(end 0.7874 0.4064)
			(stroke
				(width 0.1524)
				(type default)
			)
			(layer "F.SilkS")
		)
		(fp_line
			(start -0.7874 -0.4064)
			(end 0.7874 -0.4064)
			(stroke
				(width 0.1524)
				(type default)
			)
			(layer "F.SilkS")
		)
		(fp_line
			(start 0.7874 0.4064)
			(end -0.7874 0.4064)
			(stroke
				(width 0.1524)
				(type default)
			)
			(layer "F.SilkS")
		)
		(fp_line
			(start -0.7874 0.4064)
			(end -0.7874 -0.4064)
			(stroke
				(width 0.1524)
				(type default)
			)
			(layer "F.SilkS")
		)
		(fp_line
			(start -0.12065 -0.305054)
			(end -0.12065 -0.2794)
			(stroke
				(width 0.1)
				(type default)
			)
			(layer "F.Fab")
		)
		(fp_line
			(start -0.67945 -0.305054)
			(end -0.12065 -0.305054)
			(stroke
				(width 0.1)
				(type default)
			)
			(layer "F.Fab")
		)
		(fp_line
			(start 0.67945 -0.3048)
			(end 0.67945 0.3048)
			(stroke
				(width 0.1)
				(type default)
			)
			(layer "F.Fab")
		)
		(fp_line
			(start 0.12065 -0.3048)
			(end 0.67945 -0.3048)
			(stroke
				(width 0.1)
				(type default)
			)
			(layer "F.Fab")
		)
		(fp_line
			(start 0.12065 -0.2794)
			(end 0.12065 -0.3048)
			(stroke
				(width 0.1)
				(type default)
			)
			(layer "F.Fab")
		)
		(fp_line
			(start -0.12065 -0.2794)
			(end 0.12065 -0.2794)
			(stroke
				(width 0.1)
				(type default)
			)
			(layer "F.Fab")
		)
		(fp_line
			(start 0.120396 0.2794)
			(end -0.12065 0.2794)
			(stroke
				(width 0.1)
				(type default)
			)
			(layer "F.Fab")
		)
		(fp_line
			(start -0.12065 0.2794)
			(end -0.12065 0.3048)
			(stroke
				(width 0.1)
				(type default)
			)
			(layer "F.Fab")
		)
		(fp_line
			(start 0.67945 0.3048)
			(end 0.120396 0.3048)
			(stroke
				(width 0.1)
				(type default)
			)
			(layer "F.Fab")
		)
		(fp_line
			(start 0.120396 0.3048)
			(end 0.120396 0.2794)
			(stroke
				(width 0.1)
				(type default)
			)
			(layer "F.Fab")
		)
		(fp_line
			(start -0.12065 0.3048)
			(end -0.67945 0.3048)
			(stroke
				(width 0.1)
				(type default)
			)
			(layer "F.Fab")
		)
		(fp_line
			(start -0.67945 0.3048)
			(end -0.67945 -0.305054)
			(stroke
				(width 0.1)
				(type default)
			)
			(layer "F.Fab")
		)
		(pad "1" smd circle
			(at -0.40005 0 90)
			(size 0 0)
			(layers "F.Cu" "F.Mask" "F.Paste")
			(net "GND")
		)
		(pad "2" smd circle
			(at 0.40005 0 90)
			(size 0 0)
			(layers "F.Cu" "F.Mask" "F.Paste")
			(net "SPI_BIC1_CLK")
		)
	)
	(footprint ""
		(layer "F.Cu")
		(at 223.50476 -315.821314 180)
		(property "Reference" "PC226"
			(at 0 0 180)
			(layer "F.SilkS")
			(hide yes)
			(effects
				(font
					(size 1.27 1.27)
				)
			)
		)
		(property "Value" ""
			(at 0 0 180)
			(layer "F.Fab")
			(effects
				(font
					(size 1.27 1.27)
				)
			)
		)
		(duplicate_pad_numbers_are_jumpers no)
		(fp_line
			(start 1.524 0.762)
			(end -1.524 0.762)
			(stroke
				(width 0.1524)
				(type default)
			)
			(layer "F.SilkS")
		)
		(fp_line
			(start 1.524 -0.762)
			(end 1.524 0.762)
			(stroke
				(width 0.1524)
				(type default)
			)
			(layer "F.SilkS")
		)
		(fp_line
			(start -1.524 0.762)
			(end -1.524 -0.762)
			(stroke
				(width 0.1524)
				(type default)
			)
			(layer "F.SilkS")
		)
		(fp_line
			(start -1.524 -0.762)
			(end 1.524 -0.762)
			(stroke
				(width 0.1524)
				(type default)
			)
			(layer "F.SilkS")
		)
		(fp_line
			(start 1.1049 0.724916)
			(end 1.1049 -0.724916)
			(stroke
				(width 0.1)
				(type default)
			)
			(layer "F.Fab")
		)
		(fp_line
			(start 1.1049 -0.724916)
			(end -1.1049 -0.724916)
			(stroke
				(width 0.1)
				(type default)
			)
			(layer "F.Fab")
		)
		(fp_line
			(start -1.1049 0.724916)
			(end 1.1049 0.724916)
			(stroke
				(width 0.1)
				(type default)
			)
			(layer "F.Fab")
		)
		(fp_line
			(start -1.1049 -0.724916)
			(end -1.1049 0.724916)
			(stroke
				(width 0.1)
				(type default)
			)
			(layer "F.Fab")
		)
		(pad "1" smd rect
			(at -0.889 0)
			(size 1.016 1.27)
			(layers "F.Cu" "F.Mask" "F.Paste")
			(net "SW_P12V_P1V25_PEX1_FLT")
		)
		(pad "2" smd rect
			(at 0.889 0)
			(size 1.016 1.27)
			(layers "F.Cu" "F.Mask" "F.Paste")
			(net "GND")
		)
	)
)
